# T6G (Grand Teton) — schematic netlist excerpt (pin names and nets, part order shuffled) for the footprints in the layout excerpt that follows; sources: Cadence DE-HDL packaged netlist, KiCad conversion of 04192023_DAF0TMB3IC0_F0TG_MB_C_brd_V02_OCP.brd

C6103  Q_CAP  0.01UF 50V 10% X7R  pkg C0402  page 179 : A = P3V3_AUX_CPU0_USB2_AVDD33 ; B = GND
C456  Q_CAP  1UF 4V 20% X6S  pkg 0201  page 356 : A = P0V9_CPU1_RT3_2A_2D ; B = GND
R3476  Q_RES  33.2 1% CHIP  pkg 0402LF  page 81 : A = GPU_FPGA_THERM_OVERT_ISO_R_N ; B = GPU_FPGA_THERM_OVERT_ISO_N

(kicad_pcb
	(version 20260206)
	(generator "pcbnew")
	(generator_version "10.0")
	(general
		(thickness 1.6)
		(legacy_teardrops no)
	)
	(paper "A4")
	(title_block
		(title "04192023_DAF0TMB3IC0_F0TG_MB_C_brd_V02_OCP.brd")
		(comment 1 "Grand Teton / footprints 5883-5885 of 8354")
	)
	(layers
		(0 "F.Cu" signal "TOP")
		(4 "In1.Cu" signal "GND")
		(6 "In2.Cu" signal "IN1")
		(8 "In3.Cu" signal "GND1")
		(10 "In4.Cu" signal "IN2")
		(12 "In5.Cu" signal "GND2")
		(14 "In6.Cu" signal "IN3")
		(16 "In7.Cu" signal "GND3")
		(18 "In8.Cu" signal "VCC")
		(20 "In9.Cu" signal "VCC1")
		(22 "In10.Cu" signal "GND4")
		(24 "In11.Cu" signal "IN4")
		(26 "In12.Cu" signal "GND5")
		(28 "In13.Cu" signal "IN5")
		(30 "In14.Cu" signal "GND6")
		(32 "In15.Cu" signal "IN6")
		(34 "In16.Cu" signal "GND7")
		(2 "B.Cu" signal "BOTTOM")
		(9 "F.Adhes" user "F.Adhesive")
		(11 "B.Adhes" user "B.Adhesive")
		(13 "F.Paste" user "Package Geometry/Pastemask Top")
		(15 "B.Paste" user "Package Geometry/Pastemask Bottom")
		(5 "F.SilkS" user "Ref Des/Silkscreen Top")
		(7 "B.SilkS" user "Ref Des/Silkscreen Bottom")
		(1 "F.Mask" user "Board Geometry/Soldermask Top")
		(3 "B.Mask" user "Board Geometry/Soldermask Bottom")
		(17 "Dwgs.User" user "User.Drawings")
		(19 "Cmts.User" user "User.Comments")
		(21 "Eco1.User" user "User.Eco1")
		(23 "Eco2.User" user "User.Eco2")
		(25 "Edge.Cuts" user "Board Geometry/Outline")
		(27 "Margin" user)
		(31 "F.CrtYd" user "Package Geometry/Place Bound Top")
		(29 "B.CrtYd" user "Package Geometry/Place Bound Bottom")
		(35 "F.Fab" user "Ref Des/Assembly Top")
		(33 "B.Fab" user "Ref Des/Assembly Bottom")
	)
	(footprint ""
		(layer "B.Cu")
		(at 109.949996 -26.952448 90)
		(property "Reference" "C6103"
			(at 0 0 90)
			(layer "B.SilkS")
			(hide yes)
			(effects
				(font
					(size 1.27 1.27)
				)
				(justify mirror)
			)
		)
		(property "Value" ""
			(at 0 0 90)
			(layer "B.Fab")
			(effects
				(font
					(size 1.27 1.27)
				)
				(justify mirror)
			)
		)
		(duplicate_pad_numbers_are_jumpers no)
		(fp_line
			(start 0.7874 -0.4064)
			(end -0.7874 -0.4064)
			(stroke
				(width 0.1524)
				(type default)
			)
			(layer "B.SilkS")
		)
		(fp_line
			(start -0.7874 -0.4064)
			(end -0.7874 0.4064)
			(stroke
				(width 0.1524)
				(type default)
			)
			(layer "B.SilkS")
		)
		(fp_line
			(start 0.7874 0.4064)
			(end 0.7874 -0.4064)
			(stroke
				(width 0.1524)
				(type default)
			)
			(layer "B.SilkS")
		)
		(fp_line
			(start -0.7874 0.4064)
			(end 0.7874 0.4064)
			(stroke
				(width 0.1524)
				(type default)
			)
			(layer "B.SilkS")
		)
		(fp_line
			(start 0.67945 -0.305054)
			(end 0.12065 -0.305054)
			(stroke
				(width 0.1)
				(type default)
			)
			(layer "B.Fab")
		)
		(fp_line
			(start 0.12065 -0.305054)
			(end 0.12065 -0.2794)
			(stroke
				(width 0.1)
				(type default)
			)
			(layer "B.Fab")
		)
		(fp_line
			(start -0.12065 -0.3048)
			(end -0.67945 -0.3048)
			(stroke
				(width 0.1)
				(type default)
			)
			(layer "B.Fab")
		)
		(fp_line
			(start -0.67945 -0.3048)
			(end -0.67945 0.3048)
			(stroke
				(width 0.1)
				(type default)
			)
			(layer "B.Fab")
		)
		(fp_line
			(start 0.12065 -0.2794)
			(end -0.12065 -0.2794)
			(stroke
				(width 0.1)
				(type default)
			)
			(layer "B.Fab")
		)
		(fp_line
			(start -0.12065 -0.2794)
			(end -0.12065 -0.3048)
			(stroke
				(width 0.1)
				(type default)
			)
			(layer "B.Fab")
		)
		(fp_line
			(start 0.12065 0.2794)
			(end 0.12065 0.3048)
			(stroke
				(width 0.1)
				(type default)
			)
			(layer "B.Fab")
		)
		(fp_line
			(start -0.120396 0.2794)
			(end 0.12065 0.2794)
			(stroke
				(width 0.1)
				(type default)
			)
			(layer "B.Fab")
		)
		(fp_line
			(start 0.67945 0.3048)
			(end 0.67945 -0.305054)
			(stroke
				(width 0.1)
				(type default)
			)
			(layer "B.Fab")
		)
		(fp_line
			(start 0.12065 0.3048)
			(end 0.67945 0.3048)
			(stroke
				(width 0.1)
				(type default)
			)
			(layer "B.Fab")
		)
		(fp_line
			(start -0.120396 0.3048)
			(end -0.120396 0.2794)
			(stroke
				(width 0.1)
				(type default)
			)
			(layer "B.Fab")
		)
		(fp_line
			(start -0.67945 0.3048)
			(end -0.120396 0.3048)
			(stroke
				(width 0.1)
				(type default)
			)
			(layer "B.Fab")
		)
		(pad "1" smd circle
			(at 0.40005 0 270)
			(size 0 0)
			(layers "B.Cu" "B.Mask" "B.Paste")
			(net "P3V3_AUX_CPU0_USB2_AVDD33")
		)
		(pad "2" smd circle
			(at -0.40005 0 270)
			(size 0 0)
			(layers "B.Cu" "B.Mask" "B.Paste")
			(net "GND")
		)
	)
	(footprint ""
		(layer "B.Cu")
		(at 119.2784 -386.766562 90)
		(property "Reference" "C456"
			(at 0 0 90)
			(layer "B.SilkS")
			(hide yes)
			(effects
				(font
					(size 1.27 1.27)
				)
				(justify mirror)
			)
		)
		(property "Value" ""
			(at 0 0 90)
			(layer "B.Fab")
			(effects
				(font
					(size 1.27 1.27)
				)
				(justify mirror)
			)
		)
		(duplicate_pad_numbers_are_jumpers no)
		(fp_line
			(start 0.299974 -0.150114)
			(end -0.299974 -0.150114)
			(stroke
				(width 0.1)
				(type default)
			)
			(layer "B.Fab")
		)
		(fp_line
			(start -0.299974 -0.150114)
			(end -0.299974 0.150114)
			(stroke
				(width 0.1)
				(type default)
			)
			(layer "B.Fab")
		)
		(fp_line
			(start 0.299974 0.150114)
			(end 0.299974 -0.150114)
			(stroke
				(width 0.1)
				(type default)
			)
			(layer "B.Fab")
		)
		(fp_line
			(start -0.299974 0.150114)
			(end 0.299974 0.150114)
			(stroke
				(width 0.1)
				(type default)
			)
			(layer "B.Fab")
		)
		(pad "1" smd rect
			(at 0.2667 0 270)
			(size 0.3048 0.381)
			(layers "B.Cu" "B.Mask" "B.Paste")
			(net "P0V9_CPU1_RT3_2A_2D")
		)
		(pad "2" smd rect
			(at -0.2667 0 270)
			(size 0.3048 0.381)
			(layers "B.Cu" "B.Mask" "B.Paste")
			(net "GND")
		)
	)
	(footprint ""
		(layer "B.Cu")
		(at 197.269608 -121.753376 180)
		(property "Reference" "R3476"
			(at 0 0 0)
			(layer "B.SilkS")
			(hide yes)
			(effects
				(font
					(size 1.27 1.27)
				)
				(justify mirror)
			)
		)
		(property "Value" ""
			(at 0 0 0)
			(layer "B.Fab")
			(effects
				(font
					(size 1.27 1.27)
				)
				(justify mirror)
			)
		)
		(duplicate_pad_numbers_are_jumpers no)
		(fp_line
			(start 0.7874 0.4064)
			(end 0.7874 -0.4064)
			(stroke
				(width 0.1524)
				(type default)
			)
			(layer "B.SilkS")
		)
		(fp_line
			(start 0.7874 -0.4064)
			(end -0.7874 -0.4064)
			(stroke
				(width 0.1524)
				(type default)
			)
			(layer "B.SilkS")
		)
		(fp_line
			(start -0.7874 0.4064)
			(end 0.7874 0.4064)
			(stroke
				(width 0.1524)
				(type default)
			)
			(layer "B.SilkS")
		)
		(fp_line
			(start -0.7874 -0.4064)
			(end -0.7874 0.4064)
			(stroke
				(width 0.1524)
				(type default)
			)
			(layer "B.SilkS")
		)
		(fp_line
			(start 0.67945 0.3048)
			(end 0.67945 -0.305054)
			(stroke
				(width 0.1)
				(type default)
			)
			(layer "B.Fab")
		)
		(fp_line
			(start 0.67945 -0.305054)
			(end 0.12065 -0.305054)
			(stroke
				(width 0.1)
				(type default)
			)
			(layer "B.Fab")
		)
		(fp_line
			(start 0.12065 0.3048)
			(end 0.67945 0.3048)
			(stroke
				(width 0.1)
				(type default)
			)
			(layer "B.Fab")
		)
		(fp_line
			(start 0.12065 0.2794)
			(end 0.12065 0.3048)
			(stroke
				(width 0.1)
				(type default)
			)
			(layer "B.Fab")
		)
		(fp_line
			(start 0.12065 -0.2794)
			(end -0.12065 -0.2794)
			(stroke
				(width 0.1)
				(type default)
			)
			(layer "B.Fab")
		)
		(fp_line
			(start 0.12065 -0.305054)
			(end 0.12065 -0.2794)
			(stroke
				(width 0.1)
				(type default)
			)
			(layer "B.Fab")
		)
		(fp_line
			(start -0.120396 0.3048)
			(end -0.120396 0.2794)
			(stroke
				(width 0.1)
				(type default)
			)
			(layer "B.Fab")
		)
		(fp_line
			(start -0.120396 0.2794)
			(end 0.12065 0.2794)
			(stroke
				(width 0.1)
				(type default)
			)
			(layer "B.Fab")
		)
		(fp_line
			(start -0.12065 -0.2794)
			(end -0.12065 -0.3048)
			(stroke
				(width 0.1)
				(type default)
			)
			(layer "B.Fab")
		)
		(fp_line
			(start -0.12065 -0.3048)
			(end -0.67945 -0.3048)
			(stroke
				(width 0.1)
				(type default)
			)
			(layer "B.Fab")
		)
		(fp_line
			(start -0.67945 0.3048)
			(end -0.120396 0.3048)
			(stroke
				(width 0.1)
				(type default)
			)
			(layer "B.Fab")
		)
		(fp_line
			(start -0.67945 -0.3048)
			(end -0.67945 0.3048)
			(stroke
				(width 0.1)
				(type default)
			)
			(layer "B.Fab")
		)
		(pad "1" smd circle
			(at 0.40005 0)
			(size 0 0)
			(layers "B.Cu" "B.Mask" "B.Paste")
			(net "GPU_FPGA_THERM_OVERT_ISO_R_N")
		)
		(pad "2" smd circle
			(at -0.40005 0)
			(size 0 0)
			(layers "B.Cu" "B.Mask" "B.Paste")
			(net "GPU_FPGA_THERM_OVERT_ISO_N")
		)
	)
)
